# S9S_MB_2U (Grand Teton) — schematic parts with pin connectivity, parts 4699–4843 of 6093; source: Cadence DE-HDL packaged netlist (pstxprt.dat, pstxnet.dat, pstchip.dat)

R3080  Q_RES  130 1% CHIP  pkg 0402LF  page 256 : 1 = LED_RST_PLD_CPU0_DRAM_CD_N ; 2 = P3V3_AUX
R3081  Q_RES  130 1% CHIP  pkg 0402LF  page 256 : 1 = LED_RST_PLD_CPU0_DRAM_GH_N ; 2 = P3V3_AUX
R3082  Q_RES  130 1% CHIP  pkg 0402LF  page 256 : 1 = LED_RST_PLD_CPU1_DRAM_AB_N ; 2 = P3V3_AUX
R3083  Q_RES  130 1% CHIP  pkg 0402LF  page 256 : 1 = LED_RST_PLD_CPU1_DRAM_EF_N ; 2 = P3V3_AUX
R3084  Q_RES  130 1% CHIP  pkg 0402LF  page 256 : 1 = LED_RST_PLD_CPU1_DRAM_CD_N ; 2 = P3V3_AUX
R3085  Q_RES  130 1% CHIP  pkg 0402LF  page 256 : 1 = LED_RST_PLD_CPU1_DRAM_GH_N ; 2 = P3V3_AUX
R3086  Q_RES  130 1% CHIP  pkg 0402LF  page 253 : 1 = LED_PWRGD_PVCCD_HV_CPU0 ; 2 = P3V3_AUX
R3087  Q_RES  130 1% CHIP  pkg 0402LF  page 253 : 1 = LED_PWRGD_PVPP_HBM_CPU0 ; 2 = P3V3_AUX
R3088  Q_RES  130 1% CHIP  pkg 0402LF  page 253 : 1 = LED_PWRGD_PVCCFA_EHV_FIVRA_CPU0 ; 2 = P3V3_AUX
R3089  Q_RES  130 1% CHIP  pkg 0402LF  page 253 : 1 = LED_PWRGD_PVCCFA_EHV_CPU0 ; 2 = P3V3_AUX
R3090  Q_RES  130 1% CHIP  pkg 0402LF  page 253 : 1 = LED_PWRGD_PVNN_MAIN_CPU0 ; 2 = P3V3_AUX
R3091  Q_RES  130 1% CHIP  pkg 0402LF  page 253 : 1 = LED_PWRGD_PVCCIN_CPU0 ; 2 = P3V3_AUX
R3092  Q_RES  130 1% CHIP  pkg 0402LF  page 253 : 1 = LED_PWRGD_PVCCINFAON_CPU0 ; 2 = P3V3_AUX
R3093  Q_RES  130 1% CHIP  pkg 0402LF  page 254 : 1 = LED_PWRGD_PVCCD_HV_CPU1 ; 2 = P3V3_AUX
R3094  Q_RES  130 1% CHIP  pkg 0402LF  page 254 : 1 = LED_PWRGD_PVPP_HBM_CPU1 ; 2 = P3V3_AUX
R3095  Q_RES  130 1% CHIP  pkg 0402LF  page 254 : 1 = LED_PWRGD_PVCCFA_EHV_FIVRA_CPU1 ; 2 = P3V3_AUX
R3096  Q_RES  130 1% CHIP  pkg 0402LF  page 254 : 1 = LED_PWRGD_PVCCFA_EHV_CPU1 ; 2 = P3V3_AUX
R3097  Q_RES  130 1% CHIP  pkg 0402LF  page 254 : 1 = LED_PWRGD_PVNN_MAIN_CPU1 ; 2 = P3V3_AUX
R3098  Q_RES  130 1% CHIP  pkg 0402LF  page 254 : 1 = LED_PWRGD_PVCCIN_CPU1 ; 2 = P3V3_AUX
R3099  Q_RES  130 1% CHIP  pkg 0402LF  page 254 : 1 = LED_PWRGD_PVCCINFAON_CPU1 ; 2 = P3V3_AUX
R3100  Q_RES  130 1% CHIP  pkg 0402LF  page 252 : 1 = LED_P3V3 ; 2 = P3V3
R3101  Q_RES  470 1% CHIP  pkg 0402LF  page 252 : 1 = LED_P5V_AUX ; 2 = P5V_AUX
R3102  Q_RES  470 1% CHIP  pkg 0402LF  page 252 : 1 = LED_P5V ; 2 = P5V
R3103  Q_RES  0 5% CHIP  pkg 0402LF  page 228 : 1 = IRQ_SML0_ALERT_R_N ; 2 = IRQ_SML0_ALERT_R1_N
R3105  Q_RES  0 5% CHIP  pkg 0402LF  page 234 : 1 = SMB_BMC_SWB_SCL ; 2 = SMB_BMC_SWB_R_SCL
R3106  Q_RES  0 5% CHIP  pkg 0402LF  page 234 : 1 = SMB_BMC_SWB_SDA ; 2 = SMB_BMC_SWB_R_SDA
R3107  Q_RES  0 5% CHIP  pkg 0402LF  page 234 : 1 = SMB_2_BMC_GPU_SCL ; 2 = SMB_2_BMC_GPU_R_SCL
R3108  Q_RES  0 5% CHIP  pkg 0402LF  page 234 : 1 = SMB_2_BMC_GPU_SDA ; 2 = SMB_2_BMC_GPU_R_SDA
R3109  Q_RES  0 5% CHIP  pkg 0402LF  page 234 : 1 = SMB_1_BMC_GPU_SCL ; 2 = SMB_1_BMC_GPU_R_SCL
R3110  Q_RES  0 5% CHIP  pkg 0402LF  page 234 : 1 = SMB_1_BMC_GPU_SDA ; 2 = SMB_1_BMC_GPU_R_SDA
R3111  Q_RES  0 5% CHIP  pkg 0402LF  page 234 : 1 = I3C_BMC_SWB_SDA ; 2 = I3C_BMC_SWB_R_SDA
R3112  Q_RES  33.2 1% CHIP  pkg 0402LF  page 234 : 1 = I3C_BMC_SWB_SCL ; 2 = I3C_BMC_SWB_R_SCL
R3113  Q_RES  33.2 1% CHIP  pkg 0402LF  page 245 : 1 = SMB_FAN_3V3AUX_SCL ; 2 = SMB_FAN_3V3AUX_R_SCL
R3114  Q_RES  33.2 1% CHIP  pkg 0402LF  page 245 : 1 = SMB_FAN_3V3AUX_SDA ; 2 = SMB_FAN_3V3AUX_R_SDA
R3117  Q_RES  510K 5% EMPTY  pkg 0402LF  page 259 : 1 = P12V_AUX ; 2 = P3V3_AUX_EN
R3118  Q_RES  86.6K 1% EMPTY  pkg 0402LF  page 259 : 1 = P3V3_AUX_EN ; 2 = GND
R3123  Q_RES  0 5% CHIP  pkg 0402LF  page 236 : 1 = SMB_S3M_CPU0_PIROM_3V3AUX_SCL_R ; 2 = SMB_S3M_CPU0_PIROM_3V3AUX_SCL
R3124  Q_RES  0 5% CHIP  pkg 0402LF  page 236 : 1 = SMB_S3M_CPU0_PIROM_3V3AUX_SDA_R ; 2 = SMB_S3M_CPU0_PIROM_3V3AUX_SDA
R3125  Q_RES  0 5% CHIP  pkg 0402LF  page 236 : 1 = SMB_S3M_CPU1_PIROM_3V3AUX_SCL_R ; 2 = SMB_S3M_CPU1_PIROM_3V3AUX_SCL
R3126  Q_RES  0 5% CHIP  pkg 0402LF  page 236 : 1 = SMB_S3M_CPU1_PIROM_3V3AUX_SDA_R ; 2 = SMB_S3M_CPU1_PIROM_3V3AUX_SDA
R3127  Q_RES  10K 1% CHIP  pkg 0402LF  page 236 : 1 = P3V3_AUX ; 2 = PCA9543_S3M_INT1_N
R3130  Q_RES  10K 1% CHIP  pkg 0402LF  page 236 : 1 = P3V3_AUX ; 2 = PCA9543_S3M_INT2_N
R3131  Q_RES  10K 1% CHIP  pkg 0402LF  page 236 : 1 = P3V3_AUX ; 2 = PCA9543_S3M_INT3_N
R3132  Q_RES  100K 1% CHIP  pkg 0402LF  page 153 : 1 = GND ; 2 = FM_OCP_SFF_PWR_GOOD
R3133  Q_RES  1K 1% CHIP  pkg 0402LF  page 162 : 1 = P3V3_AUX ; 2 = OCP_V3_2_PRSNT0_R_N
R3134  Q_RES  1K 1% CHIP  pkg 0402LF  page 162 : 1 = P3V3_AUX ; 2 = OCP_V3_2_PRSNT2_R_N
R3135  Q_RES  1K 1% CHIP  pkg 0402LF  page 162 : 1 = P3V3_AUX ; 2 = OCP_V3_2_PRSNT1_R_N
R3136  Q_RES  1K 1% CHIP  pkg 0402LF  page 162 : 1 = P3V3_AUX ; 2 = OCP_V3_2_PRSNT3_R_N
R3142  Q_RES  0 5% CHIP  pkg 0402LF  page 162 : 1 = HP_LVC3_OCP_V3_2_PRSNT2_N_R ; 2 = HP_LVC3_OCP_V3_2_PRSNT2_N
R3143  Q_RES  0 5% CHIP  pkg 0402LF  page 162 : 1 = HP_LVC3_OCP_V3_2_PRSNT2_N_R ; 2 = HP_LVC3_OCP_V3_2_ATTN_OUT_SW_N
R3144  Q_RES  0 5% EMPTY  pkg 0402LF  page 156 : 1 = P12V_OCP_PWRGD_1 ; 2 = HP_LVC3_OCP_V3_1_P12V_PWRGD
R3145  Q_RES  10K 1% CHIP  pkg 0402LF  page 162 : 1 = P3V3_AUX ; 2 = HP_LVC3_OCP_V3_2_ATTN_OUT_SW_N
R3147  Q_RES  10K 1% CHIP  pkg 0402LF  page 162 : 1 = P3V3_AUX ; 2 = HP_LVC3_OCP_V3_2_PRSNT2_N
R3149  Q_RES  1K 1% EMPTY  pkg 0402LF  page 164 : 1 = P3V3_AUX ; 2 = PD_SMB_OCP2_HP_ADD2
R3150  Q_RES  1K 1% CHIP  pkg 0402LF  page 164 : 1 = PD_SMB_OCP2_HP_ADD2 ; 2 = GND
R3151  Q_RES  1K 1% EMPTY  pkg 0402LF  page 164 : 1 = P3V3_AUX ; 2 = PD_SMB_OCP2_HP_ADD1
R3152  Q_RES  1K 1% CHIP  pkg 0402LF  page 164 : 1 = PD_SMB_OCP2_HP_ADD1 ; 2 = GND
R3153  Q_RES  1K 1% EMPTY  pkg 0402LF  page 164 : 1 = P3V3_AUX ; 2 = PD_SMB_OCP2_HP_ADD0
R3154  Q_RES  1K 1% CHIP  pkg 0402LF  page 164 : 1 = PD_SMB_OCP2_HP_ADD0 ; 2 = GND
R3155  Q_RES  1K 1% CHIP  pkg 0402LF  page 164 : 1 = P3V3_AUX ; 2 = HP_LVC3_OCP_V3_2_PRSNT2
R3156  Q_RES  33.2 1% CHIP  pkg 0402LF  page 164 : 1 = SMB_PEHPCPU1_LVC3_SCL ; 2 = SMB_PEHPCPU1_LVC3_R3_SCL
R3157  Q_RES  33.2 1% CHIP  pkg 0402LF  page 164 : 1 = SMB_PEHPCPU1_LVC3_SDA ; 2 = SMB_PEHPCPU1_LVC3_R3_SDA
R3158  Q_RES  33.2 1% CHIP  pkg 0402LF  page 164 : 1 = FM_SMB_CPU1_ALERT ; 2 = FM_SMB_PEHPCPU1_PCIE_ALERT_N
R3160  Q_RES  1K 1% EMPTY  pkg 0402LF  page 158 : 1 = P3V3_AUX ; 2 = HP_OCP_V3_1_RST_R
R3162  Q_RES  4.7K 1% CHIP  pkg 0402LF  page 159 : 1 = P3V3_OCP_V3_2 ; 2 = OCP_V3_2_ID0
R3163  Q_RES  4.7K 1% EMPTY  pkg 0402LF  page 159 : 1 = OCP_V3_2_ID0 ; 2 = GND
R3164  Q_RES  10K 1% CHIP  pkg 0402LF  page 159 : 1 = GND ; 2 = OCP_V3_2_AUX_PWR_EN
R3165  Q_RES  10K 1% CHIP  pkg 0402LF  page 159 : 1 = GND ; 2 = OCP_V3_2_MAIN_PWR_EN
R3166  Q_RES  4.7K 1% EMPTY  pkg 0402LF  page 159 : 1 = P3V3_OCP_V3_2 ; 2 = OCP_V3_2_ID1
R3167  Q_RES  4.7K 1% CHIP  pkg 0402LF  page 159 : 1 = OCP_V3_2_ID1 ; 2 = GND
R3168  Q_RES  0 5% CHIP  pkg 0402LF  page 159 : 1 = OCP_V3_2_MAIN_PWR_EN ; 2 = OCP_V3_2_MAIN_PWR_EN_R
R3169  Q_RES  0 5% CHIP  pkg 0402LF  page 159 : 1 = OCP_V3_2_ISO_BIF0_EN ; 2 = OCP_V3_2_BIF0_R_N
R3170  Q_RES  0 5% CHIP  pkg 0402LF  page 159 : 1 = OCP_V3_2_ISO_BIF1_EN ; 2 = OCP_V3_2_BIF1_R_N
R3171  Q_RES  0 5% CHIP  pkg 0402LF  page 159 : 1 = OCP_V3_2_ISO_BIF2_EN ; 2 = OCP_V3_2_BIF2_R_N
R3172  Q_RES  0 5% CHIP  pkg 0402LF  page 159 : 1 = OCP_V3_2_AUX_PWR_EN ; 2 = OCP_V3_2_AUX_PWR_EN_R
R3173  Q_RES  1K 1% CHIP  pkg 0402LF  page 159 : 1 = SGPIO_OCP_V3_2_LD_N ; 2 = P3V3_OCP_V3_2
R3174  Q_RES  10K 1% CHIP  pkg 0402LF  page 159 : 1 = SGPIO_OCP_V3_2_DATAIN ; 2 = P3V3_OCP_V3_2
R3175  Q_RES  10K 1% CHIP  pkg 0402LF  page 159 : 1 = SGPIO_OCP_V3_2_DATAOUT ; 2 = GND
R3176  Q_RES  1K 1% CHIP  pkg 0402LF  page 159 : 1 = SGPIO_OCP_V3_2_CLK ; 2 = P3V3_OCP_V3_2
R3177  Q_RES  0 5% CHIP  pkg 0402LF  page 159 : 1 = USB2_5_R1_DN ; 2 = USB2_5_DN
R3178  Q_RES  0 5% CHIP  pkg 0402LF  page 159 : 1 = USB2_5_R1_DP ; 2 = USB2_5_DP
R3180  Q_RES  100 1% CHIP  pkg 0402LF  page 159 : 1 = OCP_V3_1_PRSNTA_R_N ; 2 = GND
R3181  Q_RES  27.4 1% CHIP  pkg 0402LF  page 155 : 1 = CLK_50M_NCSI_OCP_2 ; 2 = CLK_50M_NCSI_OCP_V3_2
R3182  Q_RES  10K 1% CHIP  pkg 0402LF  page 161 : 1 = P3V3_OCP_V3_2 ; 2 = IRQ_LVC3_OCP_V3_2_WAKE_N
R3183  Q_RES  10K 1% CHIP  pkg 0402LF  page 161 : 1 = P3V3_OCP_V3_2 ; 2 = PU_OCP_V3_2_WAKE_OE
R3184  Q_RES  4.7K 1% CHIP  pkg 0402LF  page 161 : 1 = P3V3_AUX ; 2 = OCP_V3_2_WAKE_BUFF_N
R3185  Q_RES  33.2 1% CHIP  pkg 0402LF  page 161 : 1 = OCP_V3_2_WAKE_BUFF_N ; 2 = OCP_V3_2_WAKE_BUFF_R_N
R3186  Q_RES  33.2 1% CHIP  pkg 0402LF  page 161 : 1 = RST_OCP_V3_2_BUF_N ; 2 = RST_PERST0_OCP_V3_2_N
R3187  Q_RES  33.2 1% CHIP  pkg 0402LF  page 161 : 1 = RST_OCP_V3_2_BUF_N ; 2 = RST_PERST1_OCP_V3_2_N
R3188  Q_RES  33.2 1% CHIP  pkg 0402LF  page 161 : 1 = RST_OCP_V3_2_BUF_N ; 2 = RST_PERST2_OCP_V3_2_N
R3189  Q_RES  33.2 1% CHIP  pkg 0402LF  page 161 : 1 = RST_OCP_V3_2_BUF_N ; 2 = RST_PERST3_OCP_V3_2_N
R3190  Q_RES  4.7K 1% CHIP  pkg 0402LF  page 161 : 1 = P3V3_AUX ; 2 = OCP_V3_2_PWRBRK_BUFF_N
R3191  Q_RES  33.2 1% CHIP  pkg 0402LF  page 161 : 1 = OCP_V3_2_PWRBRK_BUFF_N ; 2 = OCP_V3_2_PWRBRK_N
R3192  Q_RES  4.7K 1% EMPTY  pkg 0402LF  page 161 : 1 = P3V3_AUX ; 2 = IRQ_LVC3_V3_2_WAKE_BUF_N
R3193  Q_RES  33.2 1% CHIP  pkg 0402LF  page 161 : 1 = IRQ_LVC3_V3_2_WAKE_BUF_N ; 2 = IRQ_LVC3_WAKE_N
R3194  Q_RES  22 1% CHIP  pkg 0402LF  page 207 : 1 = CLK_100M_OCP_V3_2_A_R_DP ; 2 = CLK_100M_OCP_V3_2_A_DP
R3195  Q_RES  22 1% CHIP  pkg 0402LF  page 207 : 1 = CLK_100M_OCP_V3_2_A_R_DN ; 2 = CLK_100M_OCP_V3_2_A_DN
R3196  Q_RES  22 1% CHIP  pkg 0402LF  page 207 : 1 = CLK_100M_OCP_V3_2_B_R_DP ; 2 = CLK_100M_OCP_V3_2_B_DP
R3197  Q_RES  22 1% CHIP  pkg 0402LF  page 207 : 1 = CLK_100M_OCP_V3_2_B_R_DN ; 2 = CLK_100M_OCP_V3_2_B_DN
R3198  Q_RES  22 1% CHIP  pkg 0402LF  page 207 : 1 = CLK_100M_OCP_V3_2_C_R_DP ; 2 = CLK_100M_OCP_V3_2_C_DP
R3199  Q_RES  22 1% CHIP  pkg 0402LF  page 207 : 1 = CLK_100M_OCP_V3_2_C_R_DN ; 2 = CLK_100M_OCP_V3_2_C_DN
R3200  Q_RES  22 1% CHIP  pkg 0402LF  page 207 : 1 = CLK_100M_OCP_V3_2_D_R_DP ; 2 = CLK_100M_OCP_V3_2_D_DP
R3201  Q_RES  22 1% CHIP  pkg 0402LF  page 207 : 1 = CLK_100M_OCP_V3_2_D_R_DN ; 2 = CLK_100M_OCP_V3_2_D_DN
R3203  Q_RES  33.2 1% CHIP  pkg 0402LF  page 160 : 1 = OCP_V3_2_AUX_PWR_EN ; 2 = OCP_V3_2_AUX_PWR_EN_R1
R3205  Q_RES  49.9 1% CHIP  pkg 0402LF  page 160 : 1 = FB_BMC_ISOLATE_R2 ; 2 = FB_BMC_ISOLATE1
R3206  Q_RES  0 5% EMPTY  pkg 0402LF  page 160 : 1 = FM_NCSI_OCP_V3_2_R_OE ; 2 = FB_BMC_ISOLATE1
R3207  Q_RES  100K 1% CHIP  pkg 0402LF  page 160 : 1 = FB_BMC_ISOLATE1 ; 2 = GND
R3208  Q_RES  100 1% CHIP  pkg 0402LF  page 160 : 1 = OCP_V3_2_ISO_BIF0_EN ; 2 = GND
R3209  Q_RES  22 1% EMPTY  pkg 0402LF  page 160 : 1 = OCP_V3_2_RBT_ARB_IN_R ; 2 = OCP_V3_2_RBT_ARB_IN
R3210  Q_RES  22 1% EMPTY  pkg 0402LF  page 160 : 1 = NCSI_BMC_CRS_DV_R1 ; 2 = RMII_OCP_BMC_CRSDV
R3211  Q_RES  22 1% EMPTY  pkg 0402LF  page 160 : 1 = NCSI_BMC_RXD0_R1 ; 2 = RMII_OCP_BMC_RXD_0
R3212  Q_RES  22 1% EMPTY  pkg 0402LF  page 160 : 1 = NCSI_BMC_RXD1_R1 ; 2 = RMII_OCP_BMC_RXD_1
R3213  Q_RES  0 5% EMPTY  pkg 0402LF  page 160 : 1 = NCSI_BMC_TX_EN_R1 ; 2 = RMII_BMC_OCP_TX_EN
R3214  Q_RES  0 5% EMPTY  pkg 0402LF  page 160 : 1 = NCSI_BMC_TXD0_R1 ; 2 = RMII_BMC_OCP_TXD_0
R3215  Q_RES  0 5% EMPTY  pkg 0402LF  page 160 : 1 = NCSI_BMC_TXD1_R1 ; 2 = RMII_BMC_OCP_TXD_1
R3216  Q_RES  100 1% CHIP  pkg 0402LF  page 160 : 1 = OCP_V3_2_ISO_BIF1_EN ; 2 = GND
R3217  Q_RES  100 1% CHIP  pkg 0402LF  page 160 : 1 = OCP_V3_2_ISO_BIF2_EN ; 2 = GND
R3222  Q_RES  2K 1% CHIP  pkg 0402LF  page 236 : 1 = SMB_S3M_CPU0_PIROM_3V3AUX_SCL ; 2 = P3V3_AUX
R3223  Q_RES  2K 1% CHIP  pkg 0402LF  page 236 : 1 = SMB_S3M_CPU0_PIROM_3V3AUX_SDA ; 2 = P3V3_AUX
R3224  Q_RES  2K 1% CHIP  pkg 0402LF  page 236 : 1 = SMB_S3M_CPU1_PIROM_3V3AUX_SCL ; 2 = P3V3_AUX
R3225  Q_RES  2K 1% CHIP  pkg 0402LF  page 236 : 1 = SMB_S3M_CPU1_PIROM_3V3AUX_SDA ; 2 = P3V3_AUX
R3226  Q_RES  2.2K 5% EMPTY  pkg 0402LF  page 241 : 1 = SMB_1_BMC_GPU_SCL ; 2 = P3V3_AUX
R3227  Q_RES  2.2K 5% EMPTY  pkg 0402LF  page 241 : 1 = SMB_1_BMC_GPU_SDA ; 2 = P3V3_AUX
R3228  Q_RES  200 1% CHIP  pkg 0402LF  page 159 : 1 = SMB_OCP_V3_2_3V3AUX_BUF_R_SCL ; 2 = SMB_OCP_V3_2_3V3AUX_BUF_SCL
R3229  Q_RES  200 1% CHIP  pkg 0402LF  page 159 : 1 = SMB_OCP_V3_2_3V3AUX_BUF_R_SDA ; 2 = SMB_OCP_V3_2_3V3AUX_BUF_SDA
R3230  Q_RES  33.2 1% CHIP  pkg 0402LF  page 213 : 1 = FM_OCP_V3_2_PWR_GOOD ; 2 = FM_OCP_V3_2_PWR_GOOD_R
R3231  Q_RES  33.2 1% CHIP  pkg 0402LF  page 154 : 1 = OCP_SFF_AUX_PWR_EN ; 2 = OCP_SFF_AUX_PWR_EN_R4
R3232  Q_RES  100K 1% CHIP  pkg 0402LF  page 154 : 1 = RST_HP_OCP_SFF_R_N ; 2 = GND
R3233  Q_RES  0 5% CHIP  pkg 0402LF  page 154 : 1 = RST_HP_OCP_SFF_R_N ; 2 = RST_SMB_OCP_SFF_N
R3234  Q_RES  33.2 1% CHIP  pkg 0402LF  page 161 : 1 = OCP_V3_2_AUX_PWR_EN ; 2 = OCP_V3_2_AUX_PWR_EN_R3
R3235  Q_RES  100K 1% CHIP  pkg 0402LF  page 161 : 1 = RST_HP_OCP_V3_2_R_N ; 2 = GND
R3236  Q_RES  0 5% CHIP  pkg 0402LF  page 161 : 1 = RST_HP_OCP_V3_2_R_N ; 2 = RST_SMB_OCP_V3_2_N
R3237  Q_RES  0 5% CHIP  pkg 0402LF  page 154 : 1 = OCP_SFF_RBT_ARB_OUT ; 2 = OCP_SFF_RBT_ARB_IN_R
R3238  Q_RES  33.2 1% CHIP  pkg 0402LF  page 240 : 1 = SMB_OCP_SFF_3V3AUX_SCL ; 2 = SMB_OCP_SFF_3V3AUX_SCL_R0
R3239  Q_RES  33.2 1% CHIP  pkg 0402LF  page 240 : 1 = SMB_OCP_SFF_3V3AUX_SDA ; 2 = SMB_OCP_SFF_3V3AUX_SDA_R0
R3240  Q_RES  2.2K 5% EMPTY  pkg 0402LF  page 241 : 1 = SMB_OCP_SFF_3V3AUX_SCL ; 2 = P3V3_AUX
R3241  Q_RES  2.2K 5% EMPTY  pkg 0402LF  page 241 : 1 = SMB_OCP_SFF_3V3AUX_SDA ; 2 = P3V3_AUX
R3242  Q_RES  2.2K 5% EMPTY  pkg 0402LF  page 241 : 1 = SMB_OCP_V3_2_3V3AUX_SCL ; 2 = P3V3_AUX
R3243  Q_RES  2.2K 5% EMPTY  pkg 0402LF  page 241 : 1 = SMB_OCP_V3_2_3V3AUX_SDA ; 2 = P3V3_AUX
R3244  Q_RES  0 5% CHIP  pkg 0402LF  page 160 : 1 = OCP_V3_2_RBT_ARB_OUT ; 2 = OCP_V3_2_RBT_ARB_IN_R
R3249  Q_RES  10K 1% CHIP  pkg 0402LF  page 216 : 1 = P3V3_AUX ; 2 = PU_FPGA_D12_PROGRAMN
R3254  Q_RES  0 5% EMPTY  pkg 0402LF  page 240 : 1 = TP_PCIE_HPM_TXP<3> ; 2 = LED_HDD_ACTIVITY_B_N
R3263  Q_RES  0 5% CHIP  pkg 0402LF  page 238 : 1 = HP_LVC3_OCP_V3_1_R_EN ; 2 = HP_LVC3_OCP_V3_1_EN
R3264  Q_RES  0 5% CHIP  pkg 0402LF  page 238 : 1 = HP_LVC3_OCP_V3_2_R_EN ; 2 = HP_LVC3_OCP_V3_2_EN
R3265  Q_RES  4.7K 1% EMPTY  pkg 0402LF  page 166 : 1 = CLK_GEN2_GPU_FPGA_OE_OR_N ; 2 = GND
